# BASEBOARD_FAB2 (Tioga Pass) — schematic netlist excerpt (pin names and nets, part order shuffled) for the footprints in the layout excerpt that follows; sources: Cadence DE-HDL packaged netlist, KiCad conversion of Wiwynn_Tioga_Pass_MB.brd

T1D13  TEST-PAD-12P-1-GP-U  pkg DISCRET-GB1  page 258
  DP  = L1_85OHM_10INCH_DP
  DN  = L1_85OHM_10INCH_DN
  GND(0)  = GND
  GND(1)  = GND
  GND(2)  = GND
  GND(3)  = GND
  GND(4)  = GND
  GND(5)  = GND
  GND(6)  = GND
  GND(7)  = GND
  GND(8)  = GND
  GND(9)  = GND

CF3  SC22P50V2JN-4GP  5%  pkg SMD-BCG  page 201 : \1\ = VR_PVCCIN_CPU0_AIREF3 ; \2\ = ISENSE_PVCCIN_CPU0_PH3_IMON

(kicad_pcb
	(version 20260206)
	(generator "pcbnew")
	(generator_version "10.0")
	(general
		(thickness 1.6)
		(legacy_teardrops no)
	)
	(paper "A4")
	(title_block
		(title "Wiwynn_Tioga_Pass_MB.brd")
		(comment 1 "Tioga Pass / footprints 2316-2317 of 4770")
	)
	(layers
		(0 "F.Cu" signal "TOP")
		(4 "In1.Cu" signal "L2GND")
		(6 "In2.Cu" signal "L3")
		(8 "In3.Cu" signal "L4GND")
		(10 "In4.Cu" signal "L5")
		(12 "In5.Cu" signal "L6GND")
		(14 "In6.Cu" signal "L7VCC")
		(16 "In7.Cu" signal "L8VCC")
		(18 "In8.Cu" signal "L9GND")
		(20 "In9.Cu" signal "L10")
		(22 "In10.Cu" signal "L11GND")
		(24 "In11.Cu" signal "L12")
		(26 "In12.Cu" signal "L13GND")
		(2 "B.Cu" signal "BOTTOM")
		(9 "F.Adhes" user "F.Adhesive")
		(11 "B.Adhes" user "B.Adhesive")
		(13 "F.Paste" user "Package Geometry/Pastemask Top")
		(15 "B.Paste" user "Package Geometry/Pastemask Bottom")
		(5 "F.SilkS" user "Ref Des/Silkscreen Top")
		(7 "B.SilkS" user "Ref Des/Silkscreen Bottom")
		(1 "F.Mask" user "Board Geometry/Soldermask Top")
		(3 "B.Mask" user "Board Geometry/Soldermask Bottom")
		(17 "Dwgs.User" user "User.Drawings")
		(19 "Cmts.User" user "User.Comments")
		(21 "Eco1.User" user "User.Eco1")
		(23 "Eco2.User" user "User.Eco2")
		(25 "Edge.Cuts" user "Board Geometry/Outline")
		(27 "Margin" user)
		(31 "F.CrtYd" user "Package Geometry/Place Bound Top")
		(29 "B.CrtYd" user "Package Geometry/Place Bound Bottom")
		(35 "F.Fab" user "Ref Des/Assembly Top")
		(33 "B.Fab" user "Ref Des/Assembly Bottom")
	)
	(footprint ""
		(layer "F.Cu")
		(at 189.2808 -68.2498 180)
		(property "Reference" "CF3"
			(at 0 0 180)
			(layer "F.SilkS")
			(hide yes)
			(effects
				(font
					(size 1.27 1.27)
				)
			)
		)
		(property "Value" "*"
			(at 1.1811 -2.8194 180)
			(unlocked yes)
			(layer "F.Fab")
			(hide yes)
			(effects
				(font
					(size 1.27 1.016)
					(thickness 0.1524)
				)
			)
		)
		(property "Device Type" "SC22P50V2JN-4GP_SMD-BCG-SC22P5A"
			(at 1.1811 -4.3434 180)
			(unlocked yes)
			(layer "F.Fab")
			(hide yes)
			(effects
				(font
					(size 1.27 1.016)
					(thickness 0.1524)
				)
			)
		)
		(duplicate_pad_numbers_are_jumpers no)
		(fp_rect
			(start -0.4318 0.9525)
			(end 0.4318 -0.9525)
			(stroke
				(width 0)
				(type default)
			)
			(fill no)
			(layer "F.CrtYd")
		)
		(fp_rect
			(start -0.4318 0.9525)
			(end 0.4318 -0.9525)
			(stroke
				(width 0)
				(type default)
			)
			(fill no)
			(layer "F.Fab")
		)
		(pad "1" smd custom
			(at 0 -0.4445 180)
			(size 0.1524 0.1524)
			(layers "F.Cu" "F.Mask" "F.Paste")
			(net "VR_PVCCIN_CPU0_AIREF3")
			(options
				(clearance outline)
				(anchor circle)
			)
			(primitives
				(gr_poly
					(pts
						(arc
							(start 0.3048 -0.2032)
							(mid 0.275042 -0.275042)
							(end 0.2032 -0.3048)
						)
						(arc
							(start -0.2032 -0.3048)
							(mid -0.275042 -0.275042)
							(end -0.3048 -0.2032)
						)
						(arc
							(start -0.3048 0.2032)
							(mid -0.275042 0.275042)
							(end -0.2032 0.3048)
						)
						(arc
							(start 0.2032 0.3048)
							(mid 0.275042 0.275042)
							(end 0.3048 0.2032)
						)
					)
					(width 0)
					(fill yes)
				)
			)
		)
		(pad "2" smd custom
			(at 0 0.4445 180)
			(size 0.1524 0.1524)
			(layers "F.Cu" "F.Mask" "F.Paste")
			(net "ISENSE_PVCCIN_CPU0_PH3_IMON")
			(options
				(clearance outline)
				(anchor circle)
			)
			(primitives
				(gr_poly
					(pts
						(arc
							(start 0.3048 -0.2032)
							(mid 0.275042 -0.275042)
							(end 0.2032 -0.3048)
						)
						(arc
							(start -0.2032 -0.3048)
							(mid -0.275042 -0.275042)
							(end -0.3048 -0.2032)
						)
						(arc
							(start -0.3048 0.2032)
							(mid -0.275042 0.275042)
							(end -0.2032 0.3048)
						)
						(arc
							(start 0.2032 0.3048)
							(mid 0.275042 0.275042)
							(end 0.3048 0.2032)
						)
					)
					(width 0)
					(fill yes)
				)
			)
		)
	)
	(footprint ""
		(layer "F.Cu")
		(at 156.539692 -164.904674 -90)
		(property "Reference" "T1D13"
			(at 0 0 270)
			(layer "F.SilkS")
			(hide yes)
			(effects
				(font
					(size 1.27 1.27)
				)
			)
		)
		(property "Value" "*"
			(at -3.4036 -4.46405 270)
			(unlocked yes)
			(layer "F.Fab")
			(hide yes)
			(effects
				(font
					(size 0.889 0.889)
					(thickness 0.1524)
				)
			)
		)
		(property "Device Type" "TEST-PAD-12P-1-GP-U_DISCRET-GBA"
			(at -3.4036 -5.98805 270)
			(unlocked yes)
			(layer "F.Fab")
			(hide yes)
			(effects
				(font
					(size 0.889 0.889)
					(thickness 0.1524)
				)
			)
		)
		(duplicate_pad_numbers_are_jumpers no)
		(fp_line
			(start -2.3876 3.4798)
			(end -2.3876 -4.826)
			(stroke
				(width 0.1524)
				(type default)
			)
			(layer "F.SilkS")
		)
		(fp_line
			(start 2.3622 3.4798)
			(end -2.3876 3.4798)
			(stroke
				(width 0.1524)
				(type default)
			)
			(layer "F.SilkS")
		)
		(fp_line
			(start -2.3876 -4.826)
			(end 2.3622 -4.826)
			(stroke
				(width 0.1524)
				(type default)
			)
			(layer "F.SilkS")
		)
		(fp_line
			(start 2.3622 -4.826)
			(end 2.3622 3.4798)
			(stroke
				(width 0.1524)
				(type default)
			)
			(layer "F.SilkS")
		)
		(fp_rect
			(start -2.6416 3.7338)
			(end 2.6162 -5.08)
			(stroke
				(width 0)
				(type default)
			)
			(fill no)
			(layer "F.CrtYd")
		)
		(fp_rect
			(start -2.6416 3.7338)
			(end 2.6162 -5.08)
			(stroke
				(width 0)
				(type default)
			)
			(fill no)
			(layer "F.Fab")
		)
		(pad "1" smd circle
			(at 0.496824 -1.301496 270)
			(size 0.6604 0.6604)
			(layers "F.Cu" "F.Mask" "F.Paste")
			(net "L1_85OHM_10INCH_DP")
		)
		(pad "2" smd circle
			(at -0.503936 -1.301496 270)
			(size 0.6604 0.6604)
			(layers "F.Cu" "F.Mask" "F.Paste")
			(net "L1_85OHM_10INCH_DN")
		)
		(pad "3" smd custom
			(at -0.00889 0.370078 270)
			(size 0.74295 0.74295)
			(layers "F.Cu" "F.Mask" "F.Paste")
			(net "GND")
			(options
				(clearance outline)
				(anchor circle)
			)
			(primitives
				(gr_poly
					(pts
						(xy -2.1209 1.4859) (xy 2.1209 1.4859) (xy 2.1209 -1.4859) (xy 1.08585 -1.4859) (xy 1.08585 -0.4699)
						(xy -1.08585 -0.4699) (xy -1.08585 -1.4859) (xy -2.1209 -1.4859)
					)
					(width 0)
					(fill yes)
				)
			)
		)
		(pad "4" thru_hole circle
			(at 1.266444 -3.851656 270)
			(size 1.4478 1.4478)
			(drill 1.0414)
			(layers "*.Cu" "*.Mask")
			(remove_unused_layers no)
			(net "GND")
			(clearance 0.1524)
			(thermal_gap 0.1524)
		)
		(pad "5" thru_hole circle
			(at -1.273556 -3.851656 270)
			(size 1.4478 1.4478)
			(drill 1.0414)
			(layers "*.Cu" "*.Mask")
			(remove_unused_layers no)
			(net "GND")
			(clearance 0.1524)
			(thermal_gap 0.1524)
		)
		(pad "6" thru_hole circle
			(at 1.266444 2.498344 270)
			(size 1.4478 1.4478)
			(drill 1.0414)
			(layers "*.Cu" "*.Mask")
			(remove_unused_layers no)
			(net "GND")
			(clearance 0.1524)
			(thermal_gap 0.1524)
		)
		(pad "7" thru_hole circle
			(at -1.273556 2.498344 270)
			(size 1.4478 1.4478)
			(drill 1.0414)
			(layers "*.Cu" "*.Mask")
			(remove_unused_layers no)
			(net "GND")
			(clearance 0.1524)
			(thermal_gap 0.1524)
		)
		(pad "8" thru_hole circle
			(at 1.27 -0.4572 270)
			(size 0.7112 0.7112)
			(drill 0.4064)
			(layers "*.Cu" "*.Mask")
			(remove_unused_layers no)
			(net "GND")
			(clearance 0.1016)
			(thermal_gap 0.1016)
		)
		(pad "9" thru_hole circle
			(at 1.27 0.762 270)
			(size 0.7112 0.7112)
			(drill 0.4064)
			(layers "*.Cu" "*.Mask")
			(remove_unused_layers no)
			(net "GND")
			(clearance 0.1016)
			(thermal_gap 0.1016)
		)
		(pad "10" thru_hole circle
			(at -0.0254 0.762 270)
			(size 0.7112 0.7112)
			(drill 0.4064)
			(layers "*.Cu" "*.Mask")
			(remove_unused_layers no)
			(net "GND")
			(clearance 0.1016)
			(thermal_gap 0.1016)
		)
		(pad "11" thru_hole circle
			(at -1.27 0.762 270)
			(size 0.7112 0.7112)
			(drill 0.4064)
			(layers "*.Cu" "*.Mask")
			(remove_unused_layers no)
			(net "GND")
			(clearance 0.1016)
			(thermal_gap 0.1016)
		)
		(pad "12" thru_hole circle
			(at -1.27 -0.4572 270)
			(size 0.7112 0.7112)
			(drill 0.4064)
			(layers "*.Cu" "*.Mask")
			(remove_unused_layers no)
			(net "GND")
			(clearance 0.1016)
			(thermal_gap 0.1016)
		)
	)
)
